# Bryce Canyon_Front_Drive_Plane_Board_Stackup.xlsx — PCB Test Plan_HVM(0-90) (pcb-stackup)
|  | Board vendor give feedback of quantity in yellow columns based on the AQL table or description. |  |  |  |  |  |  |  |  |  |  |  |  |  |  |
|  | Wiwynn PM give feedback in blue columns |  |  |  |  |  |  |  |  |  |  |  |  |  |  |
| Person to be informed : PCB vendor, EE, SI, PM, PSM, Buyer, SQM |  |  |  |  |  |  |  |  |  |  |  |  |  |  |  |
| Simple flow : SI (test requirements) -> PM/AM (Total PCBS demand) -> Buyer -> Board Vendor (yellow column feedback) -> Buyer -> Person to be informed (Check and Track) |  |  |  |  |  |  |  |  |  |  |  |  |  |  |  |
| PO(purchase order) : If there are many POs for this PCB, 1st sample quantity is based on 1st PO, 2nd sample quantity is based on 2nd PO. |  |  |  |  |  |  |  |  |  |  |  |  |  |  |  |
| Project Name | PCB name | PCB# (1XXXX-XX) | Product Stage | Batch# | PCB Vendor | PCBs Demand | Delta-L Coupon (PCB Vendor) | Delta-L Coupon (3rd Party Lab) | Impedance Coupon (PCB Vendor) | In-board trace correlation (PCB Vendor) | X-section Analysis (PCB Vendor) | IST (3rd Party Lab) | Resin Void (PCB Vendor) | IPC-6012D (3rd Party Lab) | Note 1 |
| Bryce Canyon | FDPB | 16315-1 | HVM(0-90 days) | N/A |  |  | Yes | Yes | Yes | Yes | Yes | Yes | No | Yes | Need Test? (Yes, No) |
| Tracking Code On Both Of Coupon And PCB |  |  |  |  |  |  | Follow rules of board vendor | Follow rules of board vendor | Follow rules of board vendor | Follow rules of board vendor | Follow rules of board vendor | Follow rules of board vendor |  | Follow rules of board vendor |  |
| Test Item Acceptance Criteria |  |  |  |  |  |  | Failure Rate ≦0.3% | Failure Rate ≦0.3% | Cpk≧1.0 | Fail : 0 Variation ≦5% | Cpk≧1.0 | Fail: 0 |  | Per IPC |  |
| Test Item Sampling Quantity |  |  |  |  |  |  | AQL 1, level 1 | 30 pcs | AQL 1, level 1 | AQL 1, level 1 | 5 pcs/production lot, with max total of 30 pcs | 5 pcs/production lot, with max total of 30 pcs |  | max total of 3 pcs |  |
| Test Time(working days) |  |  |  |  |  |  | 5 | 5 | 5 | 5 | 15 | 20+ |  | 15 |  |
| Test Item Shipping Quantity |  |  |  |  |  |  |  | 30 pcs |  |  |  | 5 pcs/production lot, with max total of 30 pcs |  | 3 pcs |  |
| Shipping Address |  |  |  |  |  |  |  | 8F, 90, Sec. 1, Xintai 5th Rd., Xizhi Dist., New Taipei City 22102, Taiwan, R.O.C. |  |  |  | 8F, 90, Sec. 1, Xintai 5th Rd., Xizhi Dist., New Taipei City 22102, Taiwan, R.O.C. |  | 8F, 90, Sec. 1, Xintai 5th Rd., Xizhi Dist., New Taipei City 22102, Taiwan, R.O.C. |  |
| Receiver Name |  |  |  |  |  |  |  | Karol Lai |  |  |  | Karol Lai |  | Karol Lai |  |
| Receiver Phone# |  |  |  |  |  |  |  | 886-2-6612-7507 |  |  |  | 886-2-6612-7507 |  | Direct: 886(2) 6612-7507 |  |
